# TIMECARD (Time Appliance Project (Time Card)) — schematic netlist excerpt (pin names and nets, part order shuffled) for the footprints in the layout excerpt that follows; sources: Cadence DE-HDL packaged netlist, KiCad conversion of R4006-B0001-02_R01.brd

R481  RESISTOR  100KOHM 1%  pkg SMC_0402R_H016  page 24 : \1\ = R_FT4232_CHC_RX ; \2\ = XP3R3V_FT4232
R487  RESISTOR  4.7KOHM 1%  pkg SMC_0402R_H016  page 33 : \1\ = UNNAMED_525_CAPACITOR_I16_1 ; \2\ = UNNAMED_525_CAPACITOR_I14_1

(kicad_pcb
	(version 20260206)
	(generator "pcbnew")
	(generator_version "10.0")
	(general
		(thickness 1.6)
		(legacy_teardrops no)
	)
	(paper "A4")
	(title_block
		(title "timecard-production-celestica-r4006 — R4006-B0001-02_R01.brd")
		(comment 1 "Time Appliance Project (Time Card) / footprints 211-212 of 1113")
	)
	(layers
		(0 "F.Cu" signal "TOP")
		(4 "In1.Cu" signal "L02_GND1")
		(6 "In2.Cu" signal "L03_SIG1")
		(8 "In3.Cu" signal "L04_GND2")
		(10 "In4.Cu" signal "L05_VCC1")
		(12 "In5.Cu" signal "L06_VCC2")
		(14 "In6.Cu" signal "L07_GND3")
		(16 "In7.Cu" signal "L08_SIG2")
		(18 "In8.Cu" signal "L09_GND4")
		(2 "B.Cu" signal "BOTTOM")
		(9 "F.Adhes" user "F.Adhesive")
		(11 "B.Adhes" user "B.Adhesive")
		(13 "F.Paste" user "Package Geometry/Pastemask Top")
		(15 "B.Paste" user "Package Geometry/Pastemask Bottom")
		(5 "F.SilkS" user "Ref Des/Silkscreen Top")
		(7 "B.SilkS" user "Ref Des/Silkscreen Bottom")
		(1 "F.Mask" user "Board Geometry/Soldermask Top")
		(3 "B.Mask" user "Board Geometry/Soldermask Bottom")
		(17 "Dwgs.User" user "User.Drawings")
		(19 "Cmts.User" user "User.Comments")
		(21 "Eco1.User" user "User.Eco1")
		(23 "Eco2.User" user "User.Eco2")
		(25 "Edge.Cuts" user "Board Geometry/Outline")
		(27 "Margin" user)
		(31 "F.CrtYd" user "Package Geometry/Place Bound Top")
		(29 "B.CrtYd" user "Package Geometry/Place Bound Bottom")
		(35 "F.Fab" user "Ref Des/Assembly Top")
		(33 "B.Fab" user "Ref Des/Assembly Bottom")
	)
	(footprint ""
		(layer "F.Cu")
		(at 46.609 -75.184 -90)
		(property "Reference" "R487"
			(at 0.381 -2.45237 90)
			(unlocked yes)
			(layer "F.SilkS")
			(effects
				(font
					(size 0.7874 0.5842)
					(thickness 0.1524)
				)
			)
		)
		(property "Value" "VAL*"
			(at 0.02032 2.13233 270)
			(unlocked yes)
			(layer "F.Fab")
			(hide yes)
			(effects
				(font
					(size 0.7874 0.5842)
					(thickness 0.1524)
				)
			)
		)
		(property "Tolerance" "TOL*"
			(at 0.044704 3.05435 270)
			(unlocked yes)
			(layer "Cmts.User")
			(hide yes)
			(effects
				(font
					(size 0.7874 0.5842)
					(thickness 0.1524)
				)
			)
		)
		(property "User Part Number" "PARTNUM*"
			(at 0.02032 4.024884 270)
			(unlocked yes)
			(layer "Cmts.User")
			(hide yes)
			(effects
				(font
					(size 0.7874 0.5842)
					(thickness 0.1524)
				)
			)
		)
		(property "Device Type" "RESISTOR-G155-14701-01,4.7KOHMA"
			(at 0.008382 1.210564 270)
			(unlocked yes)
			(layer "F.Fab")
			(hide yes)
			(effects
				(font
					(size 0.7874 0.5842)
					(thickness 0.1524)
				)
			)
		)
		(duplicate_pad_numbers_are_jumpers no)
		(fp_line
			(start -1.143 0.5588)
			(end 1.143 0.5588)
			(stroke
				(width 0.1)
				(type default)
			)
			(layer "F.SilkS")
		)
		(fp_line
			(start 1.143 0.5588)
			(end 1.143 -0.5588)
			(stroke
				(width 0.1)
				(type default)
			)
			(layer "F.SilkS")
		)
		(fp_line
			(start -1.143 -0.5588)
			(end -1.143 0.5588)
			(stroke
				(width 0.1)
				(type default)
			)
			(layer "F.SilkS")
		)
		(fp_line
			(start 1.143 -0.5588)
			(end -1.143 -0.5588)
			(stroke
				(width 0.1)
				(type default)
			)
			(layer "F.SilkS")
		)
		(fp_poly
			(pts
				(xy -1.143 0.5588) (xy 1.143 0.5588) (xy 1.143 -0.5588) (xy -1.143 -0.5588)
			)
			(stroke
				(width 0)
				(type default)
			)
			(fill no)
			(layer "F.CrtYd")
		)
		(fp_line
			(start -0.508 0.3048)
			(end 0.508 0.3048)
			(stroke
				(width 0.1)
				(type default)
			)
			(layer "F.Fab")
		)
		(fp_line
			(start 0.508 0.3048)
			(end 0.508 -0.3048)
			(stroke
				(width 0.1)
				(type default)
			)
			(layer "F.Fab")
		)
		(fp_line
			(start -0.508 -0.3048)
			(end -0.508 0.3048)
			(stroke
				(width 0.1)
				(type default)
			)
			(layer "F.Fab")
		)
		(fp_line
			(start 0.508 -0.3048)
			(end -0.508 -0.3048)
			(stroke
				(width 0.1)
				(type default)
			)
			(layer "F.Fab")
		)
		(pad "1" smd rect
			(at -0.5334 0 270)
			(size 0.7112 0.6096)
			(layers "F.Cu" "F.Mask" "F.Paste")
			(net "UNNAMED_525_CAPACITOR_I16_1")
		)
		(pad "2" smd rect
			(at 0.5334 0 270)
			(size 0.7112 0.6096)
			(layers "F.Cu" "F.Mask" "F.Paste")
			(net "UNNAMED_525_CAPACITOR_I14_1")
		)
		(zone
			(layer "F.Cu")
			(hatch none 0.5)
			(connect_pads
				(clearance 0)
			)
			(min_thickness 0.25)
			(keepout
				(tracks not_allowed)
				(vias allowed)
				(pads allowed)
				(copperpour not_allowed)
				(footprints allowed)
			)
			(placement
				(enabled no)
				(sheetname "")
			)
			(fill
				(thermal_gap 0.5)
				(thermal_bridge_width 0.5)
				(island_removal_mode 0)
			)
			(polygon
				(pts
					(xy 46.3042 -75.2602) (xy 46.3042 -75.1078) (xy 46.9138 -75.1078) (xy 46.9138 -75.2602)
				)
			)
		)
		(zone
			(layer "F.Cu")
			(hatch none 0.5)
			(connect_pads
				(clearance 0)
			)
			(min_thickness 0.25)
			(keepout
				(tracks allowed)
				(vias not_allowed)
				(pads allowed)
				(copperpour not_allowed)
				(footprints allowed)
			)
			(placement
				(enabled no)
				(sheetname "")
			)
			(fill
				(thermal_gap 0.5)
				(thermal_bridge_width 0.5)
				(island_removal_mode 0)
			)
			(polygon
				(pts
					(xy 46.3042 -75.2602) (xy 46.3042 -75.1078) (xy 46.9138 -75.1078) (xy 46.9138 -75.2602)
				)
			)
		)
	)
	(footprint ""
		(layer "F.Cu")
		(at 29.845 -75.184 -90)
		(property "Reference" "R481"
			(at -0.381 -2.19837 90)
			(unlocked yes)
			(layer "F.SilkS")
			(effects
				(font
					(size 0.7874 0.5842)
					(thickness 0.1524)
				)
			)
		)
		(property "Value" "VAL*"
			(at 0.02032 2.13233 270)
			(unlocked yes)
			(layer "F.Fab")
			(hide yes)
			(effects
				(font
					(size 0.7874 0.5842)
					(thickness 0.1524)
				)
			)
		)
		(property "Tolerance" "TOL*"
			(at 0.044704 3.05435 270)
			(unlocked yes)
			(layer "Cmts.User")
			(hide yes)
			(effects
				(font
					(size 0.7874 0.5842)
					(thickness 0.1524)
				)
			)
		)
		(property "User Part Number" "PARTNUM*"
			(at 0.02032 4.024884 270)
			(unlocked yes)
			(layer "Cmts.User")
			(hide yes)
			(effects
				(font
					(size 0.7874 0.5842)
					(thickness 0.1524)
				)
			)
		)
		(property "Device Type" "RESISTOR-G155-11003-01,100KOHMA"
			(at 0.008382 1.210564 270)
			(unlocked yes)
			(layer "F.Fab")
			(hide yes)
			(effects
				(font
					(size 0.7874 0.5842)
					(thickness 0.1524)
				)
			)
		)
		(duplicate_pad_numbers_are_jumpers no)
		(fp_line
			(start -1.143 0.5588)
			(end 1.143 0.5588)
			(stroke
				(width 0.1)
				(type default)
			)
			(layer "F.SilkS")
		)
		(fp_line
			(start 1.143 0.5588)
			(end 1.143 -0.5588)
			(stroke
				(width 0.1)
				(type default)
			)
			(layer "F.SilkS")
		)
		(fp_line
			(start -1.143 -0.5588)
			(end -1.143 0.5588)
			(stroke
				(width 0.1)
				(type default)
			)
			(layer "F.SilkS")
		)
		(fp_line
			(start 1.143 -0.5588)
			(end -1.143 -0.5588)
			(stroke
				(width 0.1)
				(type default)
			)
			(layer "F.SilkS")
		)
		(fp_poly
			(pts
				(xy -1.143 0.5588) (xy 1.143 0.5588) (xy 1.143 -0.5588) (xy -1.143 -0.5588)
			)
			(stroke
				(width 0)
				(type default)
			)
			(fill no)
			(layer "F.CrtYd")
		)
		(fp_line
			(start -0.508 0.3048)
			(end 0.508 0.3048)
			(stroke
				(width 0.1)
				(type default)
			)
			(layer "F.Fab")
		)
		(fp_line
			(start 0.508 0.3048)
			(end 0.508 -0.3048)
			(stroke
				(width 0.1)
				(type default)
			)
			(layer "F.Fab")
		)
		(fp_line
			(start -0.508 -0.3048)
			(end -0.508 0.3048)
			(stroke
				(width 0.1)
				(type default)
			)
			(layer "F.Fab")
		)
		(fp_line
			(start 0.508 -0.3048)
			(end -0.508 -0.3048)
			(stroke
				(width 0.1)
				(type default)
			)
			(layer "F.Fab")
		)
		(pad "1" smd rect
			(at -0.5334 0 270)
			(size 0.7112 0.6096)
			(layers "F.Cu" "F.Mask" "F.Paste")
			(net "R_FT4232_CHC_RX")
		)
		(pad "2" smd rect
			(at 0.5334 0 270)
			(size 0.7112 0.6096)
			(layers "F.Cu" "F.Mask" "F.Paste")
			(net "XP3R3V_FT4232")
		)
		(zone
			(layer "F.Cu")
			(hatch none 0.5)
			(connect_pads
				(clearance 0)
			)
			(min_thickness 0.25)
			(keepout
				(tracks allowed)
				(vias not_allowed)
				(pads allowed)
				(copperpour not_allowed)
				(footprints allowed)
			)
			(placement
				(enabled no)
				(sheetname "")
			)
			(fill
				(thermal_gap 0.5)
				(thermal_bridge_width 0.5)
				(island_removal_mode 0)
			)
			(polygon
				(pts
					(xy 29.5402 -75.2602) (xy 29.5402 -75.1078) (xy 30.1498 -75.1078) (xy 30.1498 -75.2602)
				)
			)
		)
		(zone
			(layer "F.Cu")
			(hatch none 0.5)
			(connect_pads
				(clearance 0)
			)
			(min_thickness 0.25)
			(keepout
				(tracks not_allowed)
				(vias allowed)
				(pads allowed)
				(copperpour not_allowed)
				(footprints allowed)
			)
			(placement
				(enabled no)
				(sheetname "")
			)
			(fill
				(thermal_gap 0.5)
				(thermal_bridge_width 0.5)
				(island_removal_mode 0)
			)
			(polygon
				(pts
					(xy 29.5402 -75.2602) (xy 29.5402 -75.1078) (xy 30.1498 -75.1078) (xy 30.1498 -75.2602)
				)
			)
		)
	)
)
